(kicad_pcb
	(version 20260206)
	(generator "pcbnew")
	(generator_version "10.0")
	(general
		(thickness 1.6)
		(legacy_teardrops no)
	)
	(paper "A4")
	(title_block
		(title "9054_F0T_PDB_BD_GPU_F_V04_1213_1550_OCP.brd")
		(comment 1 "Grand Teton / footprints 575-580 of 608")
	)
	(layers
		(0 "F.Cu" signal "TOP")
		(4 "In1.Cu" signal "GND")
		(6 "In2.Cu" signal "IN1")
		(8 "In3.Cu" signal "GND1")
		(10 "In4.Cu" signal "VCC")
		(12 "In5.Cu" signal "VCC1")
		(14 "In6.Cu" signal "GND2")
		(16 "In7.Cu" signal "IN2")
		(18 "In8.Cu" signal "GND3")
		(2 "B.Cu" signal "BOTTOM")
		(9 "F.Adhes" user "F.Adhesive")
		(11 "B.Adhes" user "B.Adhesive")
		(13 "F.Paste" user "Package Geometry/Pastemask Top")
		(15 "B.Paste" user "Package Geometry/Pastemask Bottom")
		(5 "F.SilkS" user "Ref Des/Silkscreen Top")
		(7 "B.SilkS" user "Ref Des/Silkscreen Bottom")
		(1 "F.Mask" user "Board Geometry/Soldermask Top")
		(3 "B.Mask" user "Board Geometry/Soldermask Bottom")
		(17 "Dwgs.User" user "User.Drawings")
		(19 "Cmts.User" user "User.Comments")
		(21 "Eco1.User" user "User.Eco1")
		(23 "Eco2.User" user "User.Eco2")
		(25 "Edge.Cuts" user "Board Geometry/Outline")
		(27 "Margin" user)
		(31 "F.CrtYd" user "Package Geometry/Place Bound Top")
		(29 "B.CrtYd" user "Package Geometry/Place Bound Bottom")
		(35 "F.Fab" user "Ref Des/Assembly Top")
		(33 "B.Fab" user "Ref Des/Assembly Bottom")
	)
	(footprint ""
		(layer "B.Cu")
		(at 285.9024 -74.168 180)
		(property "Reference" "R5856"
			(at 0 0 0)
			(layer "B.SilkS")
			(hide yes)
			(effects
				(font
					(size 1.27 1.27)
				)
				(justify mirror)
			)
		)
		(property "Value" ""
			(at 0 0 0)
			(layer "B.Fab")
			(effects
				(font
					(size 1.27 1.27)
				)
				(justify mirror)
			)
		)
		(duplicate_pad_numbers_are_jumpers no)
		(fp_line
			(start 0.7874 0.4064)
			(end 0.7874 -0.4064)
			(stroke
				(width 0.1524)
				(type default)
			)
			(layer "B.SilkS")
		)
		(fp_line
			(start 0.7874 -0.4064)
			(end -0.7874 -0.4064)
			(stroke
				(width 0.1524)
				(type default)
			)
			(layer "B.SilkS")
		)
		(fp_line
			(start -0.7874 0.4064)
			(end 0.7874 0.4064)
			(stroke
				(width 0.1524)
				(type default)
			)
			(layer "B.SilkS")
		)
		(fp_line
			(start -0.7874 -0.4064)
			(end -0.7874 0.4064)
			(stroke
				(width 0.1524)
				(type default)
			)
			(layer "B.SilkS")
		)
		(fp_line
			(start 0.67945 0.3048)
			(end 0.67945 -0.305054)
			(stroke
				(width 0.1)
				(type default)
			)
			(layer "B.Fab")
		)
		(fp_line
			(start 0.67945 -0.305054)
			(end 0.12065 -0.305054)
			(stroke
				(width 0.1)
				(type default)
			)
			(layer "B.Fab")
		)
		(fp_line
			(start 0.12065 0.3048)
			(end 0.67945 0.3048)
			(stroke
				(width 0.1)
				(type default)
			)
			(layer "B.Fab")
		)
		(fp_line
			(start 0.12065 0.2794)
			(end 0.12065 0.3048)
			(stroke
				(width 0.1)
				(type default)
			)
			(layer "B.Fab")
		)
		(fp_line
			(start 0.12065 -0.2794)
			(end -0.12065 -0.2794)
			(stroke
				(width 0.1)
				(type default)
			)
			(layer "B.Fab")
		)
		(fp_line
			(start 0.12065 -0.305054)
			(end 0.12065 -0.2794)
			(stroke
				(width 0.1)
				(type default)
			)
			(layer "B.Fab")
		)
		(fp_line
			(start -0.120396 0.3048)
			(end -0.120396 0.2794)
			(stroke
				(width 0.1)
				(type default)
			)
			(layer "B.Fab")
		)
		(fp_line
			(start -0.120396 0.2794)
			(end 0.12065 0.2794)
			(stroke
				(width 0.1)
				(type default)
			)
			(layer "B.Fab")
		)
		(fp_line
			(start -0.12065 -0.2794)
			(end -0.12065 -0.3048)
			(stroke
				(width 0.1)
				(type default)
			)
			(layer "B.Fab")
		)
		(fp_line
			(start -0.12065 -0.3048)
			(end -0.67945 -0.3048)
			(stroke
				(width 0.1)
				(type default)
			)
			(layer "B.Fab")
		)
		(fp_line
			(start -0.67945 0.3048)
			(end -0.120396 0.3048)
			(stroke
				(width 0.1)
				(type default)
			)
			(layer "B.Fab")
		)
		(fp_line
			(start -0.67945 -0.3048)
			(end -0.67945 0.3048)
			(stroke
				(width 0.1)
				(type default)
			)
			(layer "B.Fab")
		)
		(pad "1" smd circle
			(at 0.40005 0)
			(size 0 0)
			(layers "B.Cu" "B.Mask" "B.Paste")
			(net "SMB_P52V_PDB_SDA")
		)
		(pad "2" smd circle
			(at -0.40005 0)
			(size 0 0)
			(layers "B.Cu" "B.Mask" "B.Paste")
			(net "SMB_P52V_HS1_SDAO")
		)
	)
	(footprint ""
		(layer "B.Cu")
		(at 155.621736 -79.375 -90)
		(property "Reference" "R5875"
			(at 0 0 90)
			(layer "B.SilkS")
			(hide yes)
			(effects
				(font
					(size 1.27 1.27)
				)
				(justify mirror)
			)
		)
		(property "Value" ""
			(at 0 0 90)
			(layer "B.Fab")
			(effects
				(font
					(size 1.27 1.27)
				)
				(justify mirror)
			)
		)
		(duplicate_pad_numbers_are_jumpers no)
		(fp_line
			(start -0.7874 0.4064)
			(end 0.7874 0.4064)
			(stroke
				(width 0.1524)
				(type default)
			)
			(layer "B.SilkS")
		)
		(fp_line
			(start 0.7874 0.4064)
			(end 0.7874 -0.4064)
			(stroke
				(width 0.1524)
				(type default)
			)
			(layer "B.SilkS")
		)
		(fp_line
			(start -0.7874 -0.4064)
			(end -0.7874 0.4064)
			(stroke
				(width 0.1524)
				(type default)
			)
			(layer "B.SilkS")
		)
		(fp_line
			(start 0.7874 -0.4064)
			(end -0.7874 -0.4064)
			(stroke
				(width 0.1524)
				(type default)
			)
			(layer "B.SilkS")
		)
		(fp_line
			(start -0.67945 0.3048)
			(end -0.120396 0.3048)
			(stroke
				(width 0.1)
				(type default)
			)
			(layer "B.Fab")
		)
		(fp_line
			(start -0.120396 0.3048)
			(end -0.120396 0.2794)
			(stroke
				(width 0.1)
				(type default)
			)
			(layer "B.Fab")
		)
		(fp_line
			(start 0.12065 0.3048)
			(end 0.67945 0.3048)
			(stroke
				(width 0.1)
				(type default)
			)
			(layer "B.Fab")
		)
		(fp_line
			(start 0.67945 0.3048)
			(end 0.67945 -0.305054)
			(stroke
				(width 0.1)
				(type default)
			)
			(layer "B.Fab")
		)
		(fp_line
			(start -0.120396 0.2794)
			(end 0.12065 0.2794)
			(stroke
				(width 0.1)
				(type default)
			)
			(layer "B.Fab")
		)
		(fp_line
			(start 0.12065 0.2794)
			(end 0.12065 0.3048)
			(stroke
				(width 0.1)
				(type default)
			)
			(layer "B.Fab")
		)
		(fp_line
			(start -0.12065 -0.2794)
			(end -0.12065 -0.3048)
			(stroke
				(width 0.1)
				(type default)
			)
			(layer "B.Fab")
		)
		(fp_line
			(start 0.12065 -0.2794)
			(end -0.12065 -0.2794)
			(stroke
				(width 0.1)
				(type default)
			)
			(layer "B.Fab")
		)
		(fp_line
			(start -0.67945 -0.3048)
			(end -0.67945 0.3048)
			(stroke
				(width 0.1)
				(type default)
			)
			(layer "B.Fab")
		)
		(fp_line
			(start -0.12065 -0.3048)
			(end -0.67945 -0.3048)
			(stroke
				(width 0.1)
				(type default)
			)
			(layer "B.Fab")
		)
		(fp_line
			(start 0.12065 -0.305054)
			(end 0.12065 -0.2794)
			(stroke
				(width 0.1)
				(type default)
			)
			(layer "B.Fab")
		)
		(fp_line
			(start 0.67945 -0.305054)
			(end 0.12065 -0.305054)
			(stroke
				(width 0.1)
				(type default)
			)
			(layer "B.Fab")
		)
		(pad "1" smd circle
			(at 0.40005 0 90)
			(size 0 0)
			(layers "B.Cu" "B.Mask" "B.Paste")
			(net "P52V_HS2_ADR0")
		)
		(pad "2" smd circle
			(at -0.40005 0 90)
			(size 0 0)
			(layers "B.Cu" "B.Mask" "B.Paste")
			(net "GND1_FIELD_SIGNAL")
		)
	)
	(footprint ""
		(layer "B.Cu")
		(at 278.7904 -75.565 180)
		(property "Reference" "PR21"
			(at 0 0 0)
			(layer "B.SilkS")
			(hide yes)
			(effects
				(font
					(size 1.27 1.27)
				)
				(justify mirror)
			)
		)
		(property "Value" ""
			(at 0 0 0)
			(layer "B.Fab")
			(effects
				(font
					(size 1.27 1.27)
				)
				(justify mirror)
			)
		)
		(duplicate_pad_numbers_are_jumpers no)
		(fp_line
			(start 0.7874 0.4064)
			(end 0.7874 -0.4064)
			(stroke
				(width 0.1524)
				(type default)
			)
			(layer "B.SilkS")
		)
		(fp_line
			(start 0.7874 -0.4064)
			(end -0.7874 -0.4064)
			(stroke
				(width 0.1524)
				(type default)
			)
			(layer "B.SilkS")
		)
		(fp_line
			(start -0.7874 0.4064)
			(end 0.7874 0.4064)
			(stroke
				(width 0.1524)
				(type default)
			)
			(layer "B.SilkS")
		)
		(fp_line
			(start -0.7874 -0.4064)
			(end -0.7874 0.4064)
			(stroke
				(width 0.1524)
				(type default)
			)
			(layer "B.SilkS")
		)
		(fp_line
			(start 0.67945 0.3048)
			(end 0.67945 -0.305054)
			(stroke
				(width 0.1)
				(type default)
			)
			(layer "B.Fab")
		)
		(fp_line
			(start 0.67945 -0.305054)
			(end 0.12065 -0.305054)
			(stroke
				(width 0.1)
				(type default)
			)
			(layer "B.Fab")
		)
		(fp_line
			(start 0.12065 0.3048)
			(end 0.67945 0.3048)
			(stroke
				(width 0.1)
				(type default)
			)
			(layer "B.Fab")
		)
		(fp_line
			(start 0.12065 0.2794)
			(end 0.12065 0.3048)
			(stroke
				(width 0.1)
				(type default)
			)
			(layer "B.Fab")
		)
		(fp_line
			(start 0.12065 -0.2794)
			(end -0.12065 -0.2794)
			(stroke
				(width 0.1)
				(type default)
			)
			(layer "B.Fab")
		)
		(fp_line
			(start 0.12065 -0.305054)
			(end 0.12065 -0.2794)
			(stroke
				(width 0.1)
				(type default)
			)
			(layer "B.Fab")
		)
		(fp_line
			(start -0.120396 0.3048)
			(end -0.120396 0.2794)
			(stroke
				(width 0.1)
				(type default)
			)
			(layer "B.Fab")
		)
		(fp_line
			(start -0.120396 0.2794)
			(end 0.12065 0.2794)
			(stroke
				(width 0.1)
				(type default)
			)
			(layer "B.Fab")
		)
		(fp_line
			(start -0.12065 -0.2794)
			(end -0.12065 -0.3048)
			(stroke
				(width 0.1)
				(type default)
			)
			(layer "B.Fab")
		)
		(fp_line
			(start -0.12065 -0.3048)
			(end -0.67945 -0.3048)
			(stroke
				(width 0.1)
				(type default)
			)
			(layer "B.Fab")
		)
		(fp_line
			(start -0.67945 0.3048)
			(end -0.120396 0.3048)
			(stroke
				(width 0.1)
				(type default)
			)
			(layer "B.Fab")
		)
		(fp_line
			(start -0.67945 -0.3048)
			(end -0.67945 0.3048)
			(stroke
				(width 0.1)
				(type default)
			)
			(layer "B.Fab")
		)
		(pad "1" smd circle
			(at 0.40005 0)
			(size 0 0)
			(layers "B.Cu" "B.Mask" "B.Paste")
			(net "P52V_HS1_ISET")
		)
		(pad "2" smd circle
			(at -0.40005 0)
			(size 0 0)
			(layers "B.Cu" "B.Mask" "B.Paste")
			(net "GND_FIELD_SIGNAL")
		)
	)
	(footprint ""
		(layer "B.Cu")
		(at 159.812736 -58.674)
		(property "Reference" "PC605"
			(at 0 0 0)
			(layer "B.SilkS")
			(hide yes)
			(effects
				(font
					(size 1.27 1.27)
				)
				(justify mirror)
			)
		)
		(property "Value" ""
			(at 0 0 0)
			(layer "B.Fab")
			(effects
				(font
					(size 1.27 1.27)
				)
				(justify mirror)
			)
		)
		(duplicate_pad_numbers_are_jumpers no)
		(fp_line
			(start -2.2098 -0.9398)
			(end -2.2098 0.9398)
			(stroke
				(width 0.1524)
				(type default)
			)
			(layer "B.SilkS")
		)
		(fp_line
			(start -2.2098 0.9398)
			(end 2.2098 0.9398)
			(stroke
				(width 0.1524)
				(type default)
			)
			(layer "B.SilkS")
		)
		(fp_line
			(start 2.2098 -0.9398)
			(end -2.2098 -0.9398)
			(stroke
				(width 0.1524)
				(type default)
			)
			(layer "B.SilkS")
		)
		(fp_line
			(start 2.2098 0.9398)
			(end 2.2098 -0.9398)
			(stroke
				(width 0.1524)
				(type default)
			)
			(layer "B.SilkS")
		)
		(fp_line
			(start -1.700022 -0.899922)
			(end -1.700022 0.899922)
			(stroke
				(width 0.1)
				(type default)
			)
			(layer "B.Fab")
		)
		(fp_line
			(start -1.700022 0.899922)
			(end 1.700022 0.899922)
			(stroke
				(width 0.1)
				(type default)
			)
			(layer "B.Fab")
		)
		(fp_line
			(start 1.700022 -0.899922)
			(end -1.700022 -0.899922)
			(stroke
				(width 0.1)
				(type default)
			)
			(layer "B.Fab")
		)
		(fp_line
			(start 1.700022 0.899922)
			(end 1.700022 -0.899922)
			(stroke
				(width 0.1)
				(type default)
			)
			(layer "B.Fab")
		)
		(pad "1" smd rect
			(at 1.4732 0)
			(size 1.1684 1.5748)
			(layers "B.Cu" "B.Mask" "B.Paste")
			(net "P52V_HS2_DVCC")
		)
		(pad "2" smd rect
			(at -1.4732 0)
			(size 1.1684 1.5748)
			(layers "B.Cu" "B.Mask" "B.Paste")
			(net "GND")
		)
	)
	(footprint ""
		(layer "B.Cu")
		(at 293.116 -86.487 180)
		(property "Reference" "U42"
			(at 0.3175 -2.07137 0)
			(unlocked yes)
			(layer "B.SilkS")
			(effects
				(font
					(size 0.7874 0.5842)
					(thickness 0.1524)
				)
				(justify left mirror)
			)
		)
		(property "Value" ""
			(at 0 0 0)
			(layer "B.Fab")
			(effects
				(font
					(size 1.27 1.27)
				)
				(justify mirror)
			)
		)
		(duplicate_pad_numbers_are_jumpers no)
		(fp_line
			(start 1.400048 1.100074)
			(end 1.400048 -1.100074)
			(stroke
				(width 0.1524)
				(type default)
			)
			(layer "B.SilkS")
		)
		(fp_line
			(start -1.400048 1.100074)
			(end 1.400048 1.100074)
			(stroke
				(width 0.1524)
				(type default)
			)
			(layer "B.SilkS")
		)
		(fp_line
			(start -1.400048 -1.100074)
			(end 1.400048 -1.100074)
			(stroke
				(width 0.1524)
				(type default)
			)
			(layer "B.SilkS")
		)
		(fp_line
			(start -1.400048 -1.100074)
			(end -1.400048 1.100074)
			(stroke
				(width 0.1524)
				(type default)
			)
			(layer "B.SilkS")
		)
		(fp_poly
			(pts
				(xy 1.590548 -0.649986) (xy 2.606548 -1.157986) (xy 2.606548 -0.141986)
			)
			(stroke
				(width 0)
				(type default)
			)
			(fill yes)
			(layer "B.SilkS")
		)
		(fp_line
			(start 0.674878 1.100074)
			(end 0.674878 -1.100074)
			(stroke
				(width 0.1)
				(type default)
			)
			(layer "B.Fab")
		)
		(fp_line
			(start 0.674878 -1.100074)
			(end -0.674878 -1.100074)
			(stroke
				(width 0.1)
				(type default)
			)
			(layer "B.Fab")
		)
		(fp_line
			(start -0.674878 1.100074)
			(end 0.674878 1.100074)
			(stroke
				(width 0.1)
				(type default)
			)
			(layer "B.Fab")
		)
		(fp_line
			(start -0.674878 -1.100074)
			(end -0.674878 1.100074)
			(stroke
				(width 0.1)
				(type default)
			)
			(layer "B.Fab")
		)
		(fp_poly
			(pts
				(xy 1.590548 -0.649986) (xy 2.606548 -1.157986) (xy 2.606548 -0.141986)
			)
			(stroke
				(width 0)
				(type default)
			)
			(fill yes)
			(layer "B.Fab")
		)
		(pad "1" smd rect
			(at 0.94996 -0.649986 90)
			(size 0.4318 0.6096)
			(layers "B.Cu" "B.Mask" "B.Paste")
			(net "Net_418")
		)
		(pad "2" smd rect
			(at 0.94996 0 90)
			(size 0.4318 0.6096)
			(layers "B.Cu" "B.Mask" "B.Paste")
			(net "FM_HS1_EN_BUSBAR")
		)
		(pad "3" smd rect
			(at 0.94996 0.649986 90)
			(size 0.4318 0.6096)
			(layers "B.Cu" "B.Mask" "B.Paste")
			(net "GND")
		)
		(pad "4" smd rect
			(at -0.94996 0.649986 90)
			(size 0.4318 0.6096)
			(layers "B.Cu" "B.Mask" "B.Paste")
			(net "FM_HS1_EN_BUSBAR_BUF")
		)
		(pad "5" smd rect
			(at -0.94996 -0.649986 90)
			(size 0.4318 0.6096)
			(layers "B.Cu" "B.Mask" "B.Paste")
			(net "P3V3_AUX")
		)
	)
	(footprint ""
		(layer "B.Cu")
		(at 107.188 -43.561 90)
		(property "Reference" "PR7001"
			(at 0 0 90)
			(layer "B.SilkS")
			(hide yes)
			(effects
				(font
					(size 1.27 1.27)
				)
				(justify mirror)
			)
		)
		(property "Value" ""
			(at 0 0 90)
			(layer "B.Fab")
			(effects
				(font
					(size 1.27 1.27)
				)
				(justify mirror)
			)
		)
		(duplicate_pad_numbers_are_jumpers no)
		(fp_line
			(start 0.7874 -0.4064)
			(end -0.7874 -0.4064)
			(stroke
				(width 0.1524)
				(type default)
			)
			(layer "B.SilkS")
		)
		(fp_line
			(start -0.7874 -0.4064)
			(end -0.7874 0.4064)
			(stroke
				(width 0.1524)
				(type default)
			)
			(layer "B.SilkS")
		)
		(fp_line
			(start 0.7874 0.4064)
			(end 0.7874 -0.4064)
			(stroke
				(width 0.1524)
				(type default)
			)
			(layer "B.SilkS")
		)
		(fp_line
			(start -0.7874 0.4064)
			(end 0.7874 0.4064)
			(stroke
				(width 0.1524)
				(type default)
			)
			(layer "B.SilkS")
		)
		(fp_line
			(start 0.67945 -0.305054)
			(end 0.12065 -0.305054)
			(stroke
				(width 0.1)
				(type default)
			)
			(layer "B.Fab")
		)
		(fp_line
			(start 0.12065 -0.305054)
			(end 0.12065 -0.2794)
			(stroke
				(width 0.1)
				(type default)
			)
			(layer "B.Fab")
		)
		(fp_line
			(start -0.12065 -0.3048)
			(end -0.67945 -0.3048)
			(stroke
				(width 0.1)
				(type default)
			)
			(layer "B.Fab")
		)
		(fp_line
			(start -0.67945 -0.3048)
			(end -0.67945 0.3048)
			(stroke
				(width 0.1)
				(type default)
			)
			(layer "B.Fab")
		)
		(fp_line
			(start 0.12065 -0.2794)
			(end -0.12065 -0.2794)
			(stroke
				(width 0.1)
				(type default)
			)
			(layer "B.Fab")
		)
		(fp_line
			(start -0.12065 -0.2794)
			(end -0.12065 -0.3048)
			(stroke
				(width 0.1)
				(type default)
			)
			(layer "B.Fab")
		)
		(fp_line
			(start 0.12065 0.2794)
			(end 0.12065 0.3048)
			(stroke
				(width 0.1)
				(type default)
			)
			(layer "B.Fab")
		)
		(fp_line
			(start -0.120396 0.2794)
			(end 0.12065 0.2794)
			(stroke
				(width 0.1)
				(type default)
			)
			(layer "B.Fab")
		)
		(fp_line
			(start 0.67945 0.3048)
			(end 0.67945 -0.305054)
			(stroke
				(width 0.1)
				(type default)
			)
			(layer "B.Fab")
		)
		(fp_line
			(start 0.12065 0.3048)
			(end 0.67945 0.3048)
			(stroke
				(width 0.1)
				(type default)
			)
			(layer "B.Fab")
		)
		(fp_line
			(start -0.120396 0.3048)
			(end -0.120396 0.2794)
			(stroke
				(width 0.1)
				(type default)
			)
			(layer "B.Fab")
		)
		(fp_line
			(start -0.67945 0.3048)
			(end -0.120396 0.3048)
			(stroke
				(width 0.1)
				(type default)
			)
			(layer "B.Fab")
		)
		(pad "1" smd rect
			(at 0.40005 0 90)
			(size 0.4572 0.508)
			(layers "B.Cu" "B.Mask" "B.Paste")
			(net "P52V_HS2_GATE2_R1")
		)
		(pad "2" smd rect
			(at -0.40005 0 90)
			(size 0.4572 0.508)
			(layers "B.Cu" "B.Mask" "B.Paste")
			(net "P52V_HS2_4287_GATE2_R")
		)
	)
)
